# BASEBOARD_FAB2 (Tioga Pass) — schematic netlist excerpt (pin names and nets, part order shuffled) for the footprints in the layout excerpt that follows; sources: Cadence DE-HDL packaged netlist, KiCad conversion of Wiwynn_Tioga_Pass_MB.brd

R9M20  RES  0.0 5% CHIP  pkg 0402  page 156 : A = SMB_LAN_STBY_LVC3_SCL ; B = SMB_PIROM_CPU1_SCL
R9M14  RES  20.0 1% CHIP  pkg 0402  page 163 : A = SMB_PEHPCPU1_STBY_LVC3_R_SCL ; B = SMB_PEHPCPU1_STBY_LVC3_SCL
R12W13  4D02R2F-GP  1%  pkg SMD-RG2  page 197 : \1\ = P12V_STBY ; \2\ = P12V_NVDIMM_GHJ_D

(kicad_pcb
	(version 20260206)
	(generator "pcbnew")
	(generator_version "10.0")
	(general
		(thickness 1.6)
		(legacy_teardrops no)
	)
	(paper "A4")
	(title_block
		(title "Wiwynn_Tioga_Pass_MB.brd")
		(comment 1 "Tioga Pass / footprints 3953-3955 of 4770")
	)
	(layers
		(0 "F.Cu" signal "TOP")
		(4 "In1.Cu" signal "L2GND")
		(6 "In2.Cu" signal "L3")
		(8 "In3.Cu" signal "L4GND")
		(10 "In4.Cu" signal "L5")
		(12 "In5.Cu" signal "L6GND")
		(14 "In6.Cu" signal "L7VCC")
		(16 "In7.Cu" signal "L8VCC")
		(18 "In8.Cu" signal "L9GND")
		(20 "In9.Cu" signal "L10")
		(22 "In10.Cu" signal "L11GND")
		(24 "In11.Cu" signal "L12")
		(26 "In12.Cu" signal "L13GND")
		(2 "B.Cu" signal "BOTTOM")
		(9 "F.Adhes" user "F.Adhesive")
		(11 "B.Adhes" user "B.Adhesive")
		(13 "F.Paste" user "Package Geometry/Pastemask Top")
		(15 "B.Paste" user "Package Geometry/Pastemask Bottom")
		(5 "F.SilkS" user "Ref Des/Silkscreen Top")
		(7 "B.SilkS" user "Ref Des/Silkscreen Bottom")
		(1 "F.Mask" user "Board Geometry/Soldermask Top")
		(3 "B.Mask" user "Board Geometry/Soldermask Bottom")
		(17 "Dwgs.User" user "User.Drawings")
		(19 "Cmts.User" user "User.Comments")
		(21 "Eco1.User" user "User.Eco1")
		(23 "Eco2.User" user "User.Eco2")
		(25 "Edge.Cuts" user "Board Geometry/Outline")
		(27 "Margin" user)
		(31 "F.CrtYd" user "Package Geometry/Place Bound Top")
		(29 "B.CrtYd" user "Package Geometry/Place Bound Bottom")
		(35 "F.Fab" user "Ref Des/Assembly Top")
		(33 "B.Fab" user "Ref Des/Assembly Bottom")
	)
	(footprint ""
		(layer "B.Cu")
		(at 28.564332 -31.06674 -90)
		(property "Reference" "R12W13"
			(at 0 0 90)
			(layer "B.SilkS")
			(hide yes)
			(effects
				(font
					(size 1.27 1.27)
				)
				(justify mirror)
			)
		)
		(property "Value" "*"
			(at -0.064008 -4.108196 270)
			(unlocked yes)
			(layer "B.Fab")
			(hide yes)
			(effects
				(font
					(size 1.27 1.016)
					(thickness 0.1524)
				)
				(justify mirror)
			)
		)
		(property "Device Type" "4D02R2F-GP_SMD-RG2-4D02R2F-GP,A"
			(at -0.064008 -5.632196 270)
			(unlocked yes)
			(layer "B.Fab")
			(hide yes)
			(effects
				(font
					(size 1.27 1.016)
					(thickness 0.1524)
				)
				(justify mirror)
			)
		)
		(duplicate_pad_numbers_are_jumpers no)
		(fp_line
			(start -0.508 -0.9398)
			(end 0.508 -0.9398)
			(stroke
				(width 0.1524)
				(type default)
			)
			(layer "B.SilkS")
		)
		(fp_line
			(start 0.508 -0.9398)
			(end 0.508 0.9398)
			(stroke
				(width 0.1524)
				(type default)
			)
			(layer "B.SilkS")
		)
		(fp_rect
			(start 0.508 0.9398)
			(end -0.508 -0.9398)
			(stroke
				(width 0)
				(type default)
			)
			(fill no)
			(layer "B.CrtYd")
		)
		(fp_rect
			(start 0.508 0.9398)
			(end -0.508 -0.9398)
			(stroke
				(width 0)
				(type default)
			)
			(fill no)
			(layer "B.Fab")
		)
		(pad "1" smd custom
			(at 0 -0.4445 90)
			(size 0.1397 0.1397)
			(layers "B.Cu" "B.Mask" "B.Paste")
			(net "P12V_STBY")
			(options
				(clearance outline)
				(anchor circle)
			)
			(primitives
				(gr_poly
					(pts
						(arc
							(start -0.1778 0.2794)
							(mid -0.249642 0.249642)
							(end -0.2794 0.1778)
						)
						(arc
							(start -0.2794 -0.1778)
							(mid -0.249642 -0.249642)
							(end -0.1778 -0.2794)
						)
						(arc
							(start 0.1778 -0.2794)
							(mid 0.249642 -0.249642)
							(end 0.2794 -0.1778)
						)
						(arc
							(start 0.2794 0.1778)
							(mid 0.249642 0.249642)
							(end 0.1778 0.2794)
						)
					)
					(width 0)
					(fill yes)
				)
			)
		)
		(pad "2" smd custom
			(at 0 0.4445 90)
			(size 0.1397 0.1397)
			(layers "B.Cu" "B.Mask" "B.Paste")
			(net "P12V_NVDIMM_GHJ_D")
			(options
				(clearance outline)
				(anchor circle)
			)
			(primitives
				(gr_poly
					(pts
						(arc
							(start -0.1778 0.2794)
							(mid -0.249642 0.249642)
							(end -0.2794 0.1778)
						)
						(arc
							(start -0.2794 -0.1778)
							(mid -0.249642 -0.249642)
							(end -0.1778 -0.2794)
						)
						(arc
							(start 0.1778 -0.2794)
							(mid 0.249642 -0.249642)
							(end 0.2794 -0.1778)
						)
						(arc
							(start 0.2794 0.1778)
							(mid 0.249642 0.249642)
							(end 0.1778 0.2794)
						)
					)
					(width 0)
					(fill yes)
				)
			)
		)
	)
	(footprint ""
		(layer "B.Cu")
		(at 20.14982 -134.965694 -90)
		(property "Reference" "R9M20"
			(at 0 0 90)
			(layer "B.SilkS")
			(hide yes)
			(effects
				(font
					(size 1.27 1.27)
				)
				(justify mirror)
			)
		)
		(property "Value" ""
			(at 0 0 90)
			(layer "B.Fab")
			(effects
				(font
					(size 1.27 1.27)
				)
				(justify mirror)
			)
		)
		(duplicate_pad_numbers_are_jumpers no)
		(fp_poly
			(pts
				(xy 0.2794 -0.1016) (xy -0.2794 -0.1016) (xy -0.2794 0.9906) (xy 0.2794 0.9906)
			)
			(stroke
				(width 0)
				(type default)
			)
			(fill no)
			(layer "B.CrtYd")
		)
		(fp_line
			(start -0.2794 0.9906)
			(end -0.2794 -0.1016)
			(stroke
				(width 0.1)
				(type default)
			)
			(layer "B.Fab")
		)
		(fp_line
			(start 0.2794 0.9906)
			(end -0.2794 0.9906)
			(stroke
				(width 0.1)
				(type default)
			)
			(layer "B.Fab")
		)
		(fp_line
			(start -0.2794 -0.1016)
			(end 0.2794 -0.1016)
			(stroke
				(width 0.1)
				(type default)
			)
			(layer "B.Fab")
		)
		(fp_line
			(start 0.2794 -0.1016)
			(end 0.2794 0.9906)
			(stroke
				(width 0.1)
				(type default)
			)
			(layer "B.Fab")
		)
		(pad "1" smd rect
			(at 0 0 90)
			(size 0.508 0.508)
			(layers "B.Cu" "B.Mask" "B.Paste")
			(net "SMB_LAN_STBY_LVC3_SCL")
		)
		(pad "2" smd rect
			(at 0 0.889 90)
			(size 0.508 0.508)
			(layers "B.Cu" "B.Mask" "B.Paste")
			(net "SMB_PIROM_CPU1_SCL")
		)
		(zone
			(layer "B.Cu")
			(hatch none 0.5)
			(connect_pads
				(clearance 0)
			)
			(min_thickness 0.25)
			(keepout
				(tracks not_allowed)
				(vias allowed)
				(pads allowed)
				(copperpour not_allowed)
				(footprints allowed)
			)
			(placement
				(enabled no)
				(sheetname "")
			)
			(fill
				(thermal_gap 0.5)
				(thermal_bridge_width 0.5)
				(island_removal_mode 0)
			)
			(polygon
				(pts
					(xy 19.51482 -134.711694) (xy 19.51482 -135.219694) (xy 19.89582 -135.219694) (xy 19.89582 -134.711694)
				)
			)
		)
		(zone
			(layer "B.Cu")
			(hatch none 0.5)
			(connect_pads
				(clearance 0)
			)
			(min_thickness 0.25)
			(keepout
				(tracks allowed)
				(vias not_allowed)
				(pads allowed)
				(copperpour not_allowed)
				(footprints allowed)
			)
			(placement
				(enabled no)
				(sheetname "")
			)
			(fill
				(thermal_gap 0.5)
				(thermal_bridge_width 0.5)
				(island_removal_mode 0)
			)
			(polygon
				(pts
					(xy 19.89582 -134.711694) (xy 19.89582 -135.219694) (xy 19.51482 -135.219694) (xy 19.51482 -134.711694)
				)
			)
		)
	)
	(footprint ""
		(layer "B.Cu")
		(at -3.22326 -121.47296 180)
		(property "Reference" "R9M14"
			(at 0 0 0)
			(layer "B.SilkS")
			(hide yes)
			(effects
				(font
					(size 1.27 1.27)
				)
				(justify mirror)
			)
		)
		(property "Value" ""
			(at 0 0 0)
			(layer "B.Fab")
			(effects
				(font
					(size 1.27 1.27)
				)
				(justify mirror)
			)
		)
		(duplicate_pad_numbers_are_jumpers no)
		(fp_rect
			(start 0.2794 -0.1016)
			(end -0.2794 0.9906)
			(stroke
				(width 0)
				(type default)
			)
			(fill no)
			(layer "B.CrtYd")
		)
		(fp_line
			(start 0.2794 0.9906)
			(end -0.2794 0.9906)
			(stroke
				(width 0.1)
				(type default)
			)
			(layer "B.Fab")
		)
		(fp_line
			(start 0.2794 -0.1016)
			(end 0.2794 0.9906)
			(stroke
				(width 0.1)
				(type default)
			)
			(layer "B.Fab")
		)
		(fp_line
			(start -0.2794 0.9906)
			(end -0.2794 -0.1016)
			(stroke
				(width 0.1)
				(type default)
			)
			(layer "B.Fab")
		)
		(fp_line
			(start -0.2794 -0.1016)
			(end 0.2794 -0.1016)
			(stroke
				(width 0.1)
				(type default)
			)
			(layer "B.Fab")
		)
		(pad "1" smd rect
			(at 0 0)
			(size 0.508 0.508)
			(layers "B.Cu" "B.Mask" "B.Paste")
			(net "SMB_PEHPCPU1_STBY_LVC3_R_SCL")
		)
		(pad "2" smd rect
			(at 0 0.889)
			(size 0.508 0.508)
			(layers "B.Cu" "B.Mask" "B.Paste")
			(net "SMB_PEHPCPU1_STBY_LVC3_SCL")
		)
		(zone
			(layer "B.Cu")
			(hatch none 0.5)
			(connect_pads
				(clearance 0)
			)
			(min_thickness 0.25)
			(keepout
				(tracks not_allowed)
				(vias allowed)
				(pads allowed)
				(copperpour not_allowed)
				(footprints allowed)
			)
			(placement
				(enabled no)
				(sheetname "")
			)
			(fill
				(thermal_gap 0.5)
				(thermal_bridge_width 0.5)
				(island_removal_mode 0)
			)
			(polygon
				(pts
					(xy -3.47726 -121.72696) (xy -2.96926 -121.72696) (xy -2.96926 -122.10796) (xy -3.47726 -122.10796)
				)
			)
		)
		(zone
			(layer "B.Cu")
			(hatch none 0.5)
			(connect_pads
				(clearance 0)
			)
			(min_thickness 0.25)
			(keepout
				(tracks allowed)
				(vias not_allowed)
				(pads allowed)
				(copperpour not_allowed)
				(footprints allowed)
			)
			(placement
				(enabled no)
				(sheetname "")
			)
			(fill
				(thermal_gap 0.5)
				(thermal_bridge_width 0.5)
				(island_removal_mode 0)
			)
			(polygon
				(pts
					(xy -3.47726 -121.72696) (xy -2.96926 -121.72696) (xy -2.96926 -122.10796) (xy -3.47726 -122.10796)
				)
			)
		)
	)
)
